# T6G (Grand Teton) — schematic netlist excerpt (pin names and nets, part order shuffled) for the footprints in the layout excerpt that follows; sources: Cadence DE-HDL packaged netlist, KiCad conversion of 04192023_DAF0TMB3IC0_F0TG_MB_C_brd_V02_OCP.brd

C2030  Q_CAP  15PF 50V 5% C0G  pkg 0402  page 234 : A = USB_HUB_XTAL_OUT ; B = GND
R646  Q_RES  0 5% CHIP  pkg 0402LF  page 362 : A = P0V9_RETIMER_CPU0_PMSCL ; B = P0V9_RETIMER_CPU0_PMSCL_R

(kicad_pcb
	(version 20260206)
	(generator "pcbnew")
	(generator_version "10.0")
	(general
		(thickness 1.6)
		(legacy_teardrops no)
	)
	(paper "A4")
	(title_block
		(title "04192023_DAF0TMB3IC0_F0TG_MB_C_brd_V02_OCP.brd")
		(comment 1 "Grand Teton / footprints 2278-2279 of 8354")
	)
	(layers
		(0 "F.Cu" signal "TOP")
		(4 "In1.Cu" signal "GND")
		(6 "In2.Cu" signal "IN1")
		(8 "In3.Cu" signal "GND1")
		(10 "In4.Cu" signal "IN2")
		(12 "In5.Cu" signal "GND2")
		(14 "In6.Cu" signal "IN3")
		(16 "In7.Cu" signal "GND3")
		(18 "In8.Cu" signal "VCC")
		(20 "In9.Cu" signal "VCC1")
		(22 "In10.Cu" signal "GND4")
		(24 "In11.Cu" signal "IN4")
		(26 "In12.Cu" signal "GND5")
		(28 "In13.Cu" signal "IN5")
		(30 "In14.Cu" signal "GND6")
		(32 "In15.Cu" signal "IN6")
		(34 "In16.Cu" signal "GND7")
		(2 "B.Cu" signal "BOTTOM")
		(9 "F.Adhes" user "F.Adhesive")
		(11 "B.Adhes" user "B.Adhesive")
		(13 "F.Paste" user "Package Geometry/Pastemask Top")
		(15 "B.Paste" user "Package Geometry/Pastemask Bottom")
		(5 "F.SilkS" user "Ref Des/Silkscreen Top")
		(7 "B.SilkS" user "Ref Des/Silkscreen Bottom")
		(1 "F.Mask" user "Board Geometry/Soldermask Top")
		(3 "B.Mask" user "Board Geometry/Soldermask Bottom")
		(17 "Dwgs.User" user "User.Drawings")
		(19 "Cmts.User" user "User.Comments")
		(21 "Eco1.User" user "User.Eco1")
		(23 "Eco2.User" user "User.Eco2")
		(25 "Edge.Cuts" user "Board Geometry/Outline")
		(27 "Margin" user)
		(31 "F.CrtYd" user "Package Geometry/Place Bound Top")
		(29 "B.CrtYd" user "Package Geometry/Place Bound Bottom")
		(35 "F.Fab" user "Ref Des/Assembly Top")
		(33 "B.Fab" user "Ref Des/Assembly Bottom")
	)
	(footprint ""
		(layer "F.Cu")
		(at 9.29513 -98.184208 -90)
		(property "Reference" "C2030"
			(at 0 0 270)
			(layer "F.SilkS")
			(hide yes)
			(effects
				(font
					(size 1.27 1.27)
				)
			)
		)
		(property "Value" ""
			(at 0 0 270)
			(layer "F.Fab")
			(effects
				(font
					(size 1.27 1.27)
				)
			)
		)
		(duplicate_pad_numbers_are_jumpers no)
		(fp_line
			(start -0.7874 0.4064)
			(end -0.7874 -0.4064)
			(stroke
				(width 0.1524)
				(type default)
			)
			(layer "F.SilkS")
		)
		(fp_line
			(start 0.7874 0.4064)
			(end -0.7874 0.4064)
			(stroke
				(width 0.1524)
				(type default)
			)
			(layer "F.SilkS")
		)
		(fp_line
			(start -0.7874 -0.4064)
			(end 0.7874 -0.4064)
			(stroke
				(width 0.1524)
				(type default)
			)
			(layer "F.SilkS")
		)
		(fp_line
			(start 0.7874 -0.4064)
			(end 0.7874 0.4064)
			(stroke
				(width 0.1524)
				(type default)
			)
			(layer "F.SilkS")
		)
		(fp_line
			(start -0.67945 0.3048)
			(end -0.67945 -0.305054)
			(stroke
				(width 0.1)
				(type default)
			)
			(layer "F.Fab")
		)
		(fp_line
			(start -0.12065 0.3048)
			(end -0.67945 0.3048)
			(stroke
				(width 0.1)
				(type default)
			)
			(layer "F.Fab")
		)
		(fp_line
			(start 0.120396 0.3048)
			(end 0.120396 0.2794)
			(stroke
				(width 0.1)
				(type default)
			)
			(layer "F.Fab")
		)
		(fp_line
			(start 0.67945 0.3048)
			(end 0.120396 0.3048)
			(stroke
				(width 0.1)
				(type default)
			)
			(layer "F.Fab")
		)
		(fp_line
			(start -0.12065 0.2794)
			(end -0.12065 0.3048)
			(stroke
				(width 0.1)
				(type default)
			)
			(layer "F.Fab")
		)
		(fp_line
			(start 0.120396 0.2794)
			(end -0.12065 0.2794)
			(stroke
				(width 0.1)
				(type default)
			)
			(layer "F.Fab")
		)
		(fp_line
			(start -0.12065 -0.2794)
			(end 0.12065 -0.2794)
			(stroke
				(width 0.1)
				(type default)
			)
			(layer "F.Fab")
		)
		(fp_line
			(start 0.12065 -0.2794)
			(end 0.12065 -0.3048)
			(stroke
				(width 0.1)
				(type default)
			)
			(layer "F.Fab")
		)
		(fp_line
			(start 0.12065 -0.3048)
			(end 0.67945 -0.3048)
			(stroke
				(width 0.1)
				(type default)
			)
			(layer "F.Fab")
		)
		(fp_line
			(start 0.67945 -0.3048)
			(end 0.67945 0.3048)
			(stroke
				(width 0.1)
				(type default)
			)
			(layer "F.Fab")
		)
		(fp_line
			(start -0.67945 -0.305054)
			(end -0.12065 -0.305054)
			(stroke
				(width 0.1)
				(type default)
			)
			(layer "F.Fab")
		)
		(fp_line
			(start -0.12065 -0.305054)
			(end -0.12065 -0.2794)
			(stroke
				(width 0.1)
				(type default)
			)
			(layer "F.Fab")
		)
		(pad "1" smd circle
			(at -0.40005 0 270)
			(size 0 0)
			(layers "F.Cu" "F.Mask" "F.Paste")
			(net "USB_HUB_XTAL_OUT")
		)
		(pad "2" smd circle
			(at 0.40005 0 270)
			(size 0 0)
			(layers "F.Cu" "F.Mask" "F.Paste")
			(net "GND")
		)
	)
	(footprint ""
		(layer "F.Cu")
		(at 442.077602 -429.37811 -90)
		(property "Reference" "R646"
			(at 0 0 270)
			(layer "F.SilkS")
			(hide yes)
			(effects
				(font
					(size 1.27 1.27)
				)
			)
		)
		(property "Value" ""
			(at 0 0 270)
			(layer "F.Fab")
			(effects
				(font
					(size 1.27 1.27)
				)
			)
		)
		(duplicate_pad_numbers_are_jumpers no)
		(fp_line
			(start -0.7874 0.4064)
			(end -0.7874 -0.4064)
			(stroke
				(width 0.1524)
				(type default)
			)
			(layer "F.SilkS")
		)
		(fp_line
			(start 0.7874 0.4064)
			(end -0.7874 0.4064)
			(stroke
				(width 0.1524)
				(type default)
			)
			(layer "F.SilkS")
		)
		(fp_line
			(start -0.7874 -0.4064)
			(end 0.7874 -0.4064)
			(stroke
				(width 0.1524)
				(type default)
			)
			(layer "F.SilkS")
		)
		(fp_line
			(start 0.7874 -0.4064)
			(end 0.7874 0.4064)
			(stroke
				(width 0.1524)
				(type default)
			)
			(layer "F.SilkS")
		)
		(fp_line
			(start -0.67945 0.3048)
			(end -0.67945 -0.305054)
			(stroke
				(width 0.1)
				(type default)
			)
			(layer "F.Fab")
		)
		(fp_line
			(start -0.12065 0.3048)
			(end -0.67945 0.3048)
			(stroke
				(width 0.1)
				(type default)
			)
			(layer "F.Fab")
		)
		(fp_line
			(start 0.120396 0.3048)
			(end 0.120396 0.2794)
			(stroke
				(width 0.1)
				(type default)
			)
			(layer "F.Fab")
		)
		(fp_line
			(start 0.67945 0.3048)
			(end 0.120396 0.3048)
			(stroke
				(width 0.1)
				(type default)
			)
			(layer "F.Fab")
		)
		(fp_line
			(start -0.12065 0.2794)
			(end -0.12065 0.3048)
			(stroke
				(width 0.1)
				(type default)
			)
			(layer "F.Fab")
		)
		(fp_line
			(start 0.120396 0.2794)
			(end -0.12065 0.2794)
			(stroke
				(width 0.1)
				(type default)
			)
			(layer "F.Fab")
		)
		(fp_line
			(start -0.12065 -0.2794)
			(end 0.12065 -0.2794)
			(stroke
				(width 0.1)
				(type default)
			)
			(layer "F.Fab")
		)
		(fp_line
			(start 0.12065 -0.2794)
			(end 0.12065 -0.3048)
			(stroke
				(width 0.1)
				(type default)
			)
			(layer "F.Fab")
		)
		(fp_line
			(start 0.12065 -0.3048)
			(end 0.67945 -0.3048)
			(stroke
				(width 0.1)
				(type default)
			)
			(layer "F.Fab")
		)
		(fp_line
			(start 0.67945 -0.3048)
			(end 0.67945 0.3048)
			(stroke
				(width 0.1)
				(type default)
			)
			(layer "F.Fab")
		)
		(fp_line
			(start -0.67945 -0.305054)
			(end -0.12065 -0.305054)
			(stroke
				(width 0.1)
				(type default)
			)
			(layer "F.Fab")
		)
		(fp_line
			(start -0.12065 -0.305054)
			(end -0.12065 -0.2794)
			(stroke
				(width 0.1)
				(type default)
			)
			(layer "F.Fab")
		)
		(pad "1" smd circle
			(at -0.40005 0 270)
			(size 0 0)
			(layers "F.Cu" "F.Mask" "F.Paste")
			(net "P0V9_RETIMER_CPU0_PMSCL")
		)
		(pad "2" smd circle
			(at 0.40005 0 270)
			(size 0 0)
			(layers "F.Cu" "F.Mask" "F.Paste")
			(net "P0V9_RETIMER_CPU0_PMSCL_R")
		)
	)
)
